(kicad_pcb
	(version 20260206)
	(generator "pcbnew")
	(generator_version "10.0")
	(general
		(thickness 1.6)
		(legacy_teardrops no)
	)
	(paper "A4")
	(title_block
		(title "Bryce Canyon_SCC_16316-1_OCP.brd")
		(comment 1 "Bryce Canyon / footprints 658-666 of 1561")
	)
	(layers
		(0 "F.Cu" signal "TOP")
		(4 "In1.Cu" signal "L2GND")
		(6 "In2.Cu" signal "L3")
		(8 "In3.Cu" signal "L4VCC")
		(10 "In4.Cu" signal "L5VCC")
		(12 "In5.Cu" signal "L6")
		(14 "In6.Cu" signal "L7GND")
		(2 "B.Cu" signal "BOTTOM")
		(9 "F.Adhes" user "F.Adhesive")
		(11 "B.Adhes" user "B.Adhesive")
		(13 "F.Paste" user "Package Geometry/Pastemask Top")
		(15 "B.Paste" user "Package Geometry/Pastemask Bottom")
		(5 "F.SilkS" user "Ref Des/Silkscreen Top")
		(7 "B.SilkS" user "Ref Des/Silkscreen Bottom")
		(1 "F.Mask" user "Board Geometry/Soldermask Top")
		(3 "B.Mask" user "Board Geometry/Soldermask Bottom")
		(17 "Dwgs.User" user "User.Drawings")
		(19 "Cmts.User" user "User.Comments")
		(21 "Eco1.User" user "User.Eco1")
		(23 "Eco2.User" user "User.Eco2")
		(25 "Edge.Cuts" user "Board Geometry/Outline")
		(27 "Margin" user)
		(31 "F.CrtYd" user "Package Geometry/Place Bound Top")
		(29 "B.CrtYd" user "Package Geometry/Place Bound Bottom")
		(35 "F.Fab" user "Ref Des/Assembly Top")
		(33 "B.Fab" user "Ref Des/Assembly Bottom")
	)
	(footprint ""
		(layer "F.Cu")
		(at 138.482324 -104.872028 180)
		(property "Reference" "R24"
			(at 0 0 180)
			(layer "F.SilkS")
			(hide yes)
			(effects
				(font
					(size 1.27 1.27)
				)
			)
		)
		(property "Value" "0R5J-5-GP"
			(at 0 -8.9535 180)
			(unlocked yes)
			(layer "F.Fab")
			(hide yes)
			(effects
				(font
					(size 1.27 1.016)
					(thickness 0.1524)
				)
			)
		)
		(property "Device Type" "R805H24"
			(at 0 -10.6299 180)
			(unlocked yes)
			(layer "F.Fab")
			(hide yes)
			(effects
				(font
					(size 1.27 1.016)
					(thickness 0.1524)
				)
			)
		)
		(duplicate_pad_numbers_are_jumpers no)
		(fp_line
			(start 0.889 1.7018)
			(end 0.889 -0.508)
			(stroke
				(width 0.1524)
				(type default)
			)
			(layer "F.SilkS")
		)
		(fp_line
			(start 0.889 -1.7018)
			(end 0.889 -0.381)
			(stroke
				(width 0.1524)
				(type default)
			)
			(layer "F.SilkS")
		)
		(fp_line
			(start 0.889 -1.7018)
			(end -0.889 -1.7018)
			(stroke
				(width 0.1524)
				(type default)
			)
			(layer "F.SilkS")
		)
		(fp_line
			(start -0.889 1.7018)
			(end 0.889 1.7018)
			(stroke
				(width 0.1524)
				(type default)
			)
			(layer "F.SilkS")
		)
		(fp_line
			(start -0.889 0.0762)
			(end -0.889 1.7018)
			(stroke
				(width 0.1524)
				(type default)
			)
			(layer "F.SilkS")
		)
		(fp_line
			(start -0.889 -1.7018)
			(end -0.889 0.2794)
			(stroke
				(width 0.1524)
				(type default)
			)
			(layer "F.SilkS")
		)
		(fp_poly
			(pts
				(xy 0.9652 -1.778) (xy 0.9652 1.778) (xy -0.9652 1.778) (xy -0.9652 -1.778)
			)
			(stroke
				(width 0)
				(type default)
			)
			(fill no)
			(layer "F.CrtYd")
		)
		(fp_rect
			(start -0.9652 1.778)
			(end 0.9652 -1.778)
			(stroke
				(width 0)
				(type default)
			)
			(fill no)
			(layer "F.Fab")
		)
		(pad "1" smd rect
			(at 0 -0.9652 180)
			(size 1.397 1.143)
			(layers "F.Cu" "F.Mask" "F.Paste")
			(net "P1V5_E")
		)
		(pad "2" smd rect
			(at 0 0.9652 180)
			(size 1.397 1.143)
			(layers "F.Cu" "F.Mask" "F.Paste")
			(net "P1V5_E_OUT")
		)
	)
	(footprint ""
		(layer "F.Cu")
		(at 181.965092 -116.771166 90)
		(property "Reference" "C109"
			(at 0 0 90)
			(layer "F.SilkS")
			(hide yes)
			(effects
				(font
					(size 1.27 1.27)
				)
			)
		)
		(property "Value" "SC10U6D3V5KX-4GP"
			(at -0.0762 -6.1214 90)
			(unlocked yes)
			(layer "F.Fab")
			(hide yes)
			(effects
				(font
					(size 1.016 1.016)
					(thickness 0.1524)
				)
			)
		)
		(property "Device Type" "C805H58"
			(at -0.0762 -8.1534 90)
			(unlocked yes)
			(layer "F.Fab")
			(hide yes)
			(effects
				(font
					(size 1.016 1.016)
					(thickness 0.1524)
				)
			)
		)
		(duplicate_pad_numbers_are_jumpers no)
		(fp_line
			(start 0.635 0)
			(end -0.635 0)
			(stroke
				(width 0.508)
				(type default)
			)
			(layer "F.SilkS")
		)
		(fp_rect
			(start -0.9652 1.778)
			(end 0.9652 -1.778)
			(stroke
				(width 0)
				(type default)
			)
			(fill no)
			(layer "F.CrtYd")
		)
		(fp_poly
			(pts
				(xy -0.9652 -1.778) (xy 0.9652 -1.778) (xy 0.9652 1.778) (xy -0.9652 1.778)
			)
			(stroke
				(width 0)
				(type default)
			)
			(fill no)
			(layer "F.Fab")
		)
		(pad "1" smd rect
			(at 0 -0.9652 90)
			(size 1.397 1.143)
			(layers "F.Cu" "F.Mask" "F.Paste")
			(net "P1V8_E_OUT")
		)
		(pad "2" smd rect
			(at 0 0.9652 90)
			(size 1.397 1.143)
			(layers "F.Cu" "F.Mask" "F.Paste")
			(net "GND")
		)
	)
	(footprint ""
		(layer "F.Cu")
		(at 175.6156 -99.7966)
		(property "Reference" "C662"
			(at 0 0 0)
			(layer "F.SilkS")
			(hide yes)
			(effects
				(font
					(size 1.27 1.27)
				)
			)
		)
		(property "Value" "SCD01U25V2KX-3GP"
			(at 1.1811 -2.7051 0)
			(unlocked yes)
			(layer "F.Fab")
			(hide yes)
			(effects
				(font
					(size 1.016 1.016)
					(thickness 0.1524)
				)
			)
		)
		(property "Device Type" "C402H22"
			(at 1.1811 -4.2291 0)
			(unlocked yes)
			(layer "F.Fab")
			(hide yes)
			(effects
				(font
					(size 1.016 1.016)
					(thickness 0.1524)
				)
			)
		)
		(duplicate_pad_numbers_are_jumpers no)
		(fp_rect
			(start -0.4318 0.9525)
			(end 0.4318 -0.9525)
			(stroke
				(width 0)
				(type default)
			)
			(fill no)
			(layer "F.CrtYd")
		)
		(fp_rect
			(start -0.4318 0.9525)
			(end 0.4318 -0.9525)
			(stroke
				(width 0)
				(type default)
			)
			(fill no)
			(layer "F.Fab")
		)
		(pad "1" smd custom
			(at 0 -0.4445)
			(size 0.1524 0.1524)
			(layers "F.Cu" "F.Mask" "F.Paste")
			(net "VT235_VDES_RCC")
			(options
				(clearance outline)
				(anchor circle)
			)
			(primitives
				(gr_poly
					(pts
						(arc
							(start 0.3048 -0.2032)
							(mid 0.275042 -0.275042)
							(end 0.2032 -0.3048)
						)
						(arc
							(start -0.2032 -0.3048)
							(mid -0.275042 -0.275042)
							(end -0.3048 -0.2032)
						)
						(arc
							(start -0.3048 0.2032)
							(mid -0.275042 0.275042)
							(end -0.2032 0.3048)
						)
						(arc
							(start 0.2032 0.3048)
							(mid 0.275042 0.275042)
							(end 0.3048 0.2032)
						)
					)
					(width 0)
					(fill yes)
				)
			)
		)
		(pad "2" smd custom
			(at 0 0.4445)
			(size 0.1524 0.1524)
			(layers "F.Cu" "F.Mask" "F.Paste")
			(net "VT235_VDES")
			(options
				(clearance outline)
				(anchor circle)
			)
			(primitives
				(gr_poly
					(pts
						(arc
							(start 0.3048 -0.2032)
							(mid 0.275042 -0.275042)
							(end 0.2032 -0.3048)
						)
						(arc
							(start -0.2032 -0.3048)
							(mid -0.275042 -0.275042)
							(end -0.3048 -0.2032)
						)
						(arc
							(start -0.3048 0.2032)
							(mid -0.275042 0.275042)
							(end -0.2032 0.3048)
						)
						(arc
							(start 0.2032 0.3048)
							(mid 0.275042 0.275042)
							(end 0.3048 0.2032)
						)
					)
					(width 0)
					(fill yes)
				)
			)
		)
	)
	(footprint ""
		(layer "F.Cu")
		(at 24.69642 -30.94228)
		(property "Reference" "C739"
			(at 0 0 0)
			(layer "F.SilkS")
			(hide yes)
			(effects
				(font
					(size 1.27 1.27)
				)
			)
		)
		(property "Value" "SC2D2U16V5KX-1GP"
			(at -0.0762 -6.1214 0)
			(unlocked yes)
			(layer "F.Fab")
			(hide yes)
			(effects
				(font
					(size 1.016 1.016)
					(thickness 0.1524)
				)
			)
		)
		(property "Device Type" "C805H58"
			(at -0.0762 -8.1534 0)
			(unlocked yes)
			(layer "F.Fab")
			(hide yes)
			(effects
				(font
					(size 1.016 1.016)
					(thickness 0.1524)
				)
			)
		)
		(duplicate_pad_numbers_are_jumpers no)
		(fp_line
			(start 0.635 0)
			(end -0.635 0)
			(stroke
				(width 0.508)
				(type default)
			)
			(layer "F.SilkS")
		)
		(fp_rect
			(start -0.9652 1.778)
			(end 0.9652 -1.778)
			(stroke
				(width 0)
				(type default)
			)
			(fill no)
			(layer "F.CrtYd")
		)
		(fp_poly
			(pts
				(xy -0.9652 -1.778) (xy 0.9652 -1.778) (xy 0.9652 1.778) (xy -0.9652 1.778)
			)
			(stroke
				(width 0)
				(type default)
			)
			(fill no)
			(layer "F.Fab")
		)
		(pad "1" smd rect
			(at 0 -0.9652)
			(size 1.397 1.143)
			(layers "F.Cu" "F.Mask" "F.Paste")
			(net "P12V_MAIN")
		)
		(pad "2" smd rect
			(at 0 0.9652)
			(size 1.397 1.143)
			(layers "F.Cu" "F.Mask" "F.Paste")
			(net "GND")
		)
	)
	(footprint ""
		(layer "F.Cu")
		(at 107.024678 -86.665054)
		(property "Reference" "TP39"
			(at 0 0 0)
			(layer "F.SilkS")
			(hide yes)
			(effects
				(font
					(size 1.27 1.27)
				)
			)
		)
		(property "Value" "TPAD28-2-GP"
			(at -0.0127 -1.6637 0)
			(unlocked yes)
			(layer "F.Fab")
			(hide yes)
			(effects
				(font
					(size 1.016 1.016)
					(thickness 0.1524)
				)
			)
		)
		(property "Device Type" "TPAD28"
			(at -0.0127 -3.1877 0)
			(unlocked yes)
			(layer "F.Fab")
			(hide yes)
			(effects
				(font
					(size 1.016 1.016)
					(thickness 0.1524)
				)
			)
		)
		(duplicate_pad_numbers_are_jumpers no)
		(fp_poly
			(pts
				(arc
					(start 0.3556 0)
					(mid -0.3556 0)
					(end 0.3556 0)
				)
			)
			(stroke
				(width 0)
				(type default)
			)
			(fill no)
			(layer "F.CrtYd")
		)
		(fp_poly
			(pts
				(arc
					(start 0.6096 0)
					(mid -0.6096 0)
					(end 0.6096 0)
				)
			)
			(stroke
				(width 0)
				(type default)
			)
			(fill no)
			(layer "F.Fab")
		)
		(pad "1" smd circle
			(at 0 0)
			(size 0.7112 0.7112)
			(layers "F.Cu" "F.Mask" "F.Paste")
			(net "JTAG_EXP_TDO")
		)
	)
	(footprint ""
		(layer "F.Cu")
		(at 12.8778 -94.801182 180)
		(property "Reference" "R430"
			(at 0 0 180)
			(layer "F.SilkS")
			(hide yes)
			(effects
				(font
					(size 1.27 1.27)
				)
			)
		)
		(property "Value" "200KR2F-L-GP"
			(at 0.064008 -3.993896 180)
			(unlocked yes)
			(layer "F.Fab")
			(hide yes)
			(effects
				(font
					(size 1.016 1.016)
					(thickness 0.1524)
				)
			)
		)
		(property "Device Type" "R402H16"
			(at 0.064008 -5.517896 180)
			(unlocked yes)
			(layer "F.Fab")
			(hide yes)
			(effects
				(font
					(size 1.016 1.016)
					(thickness 0.1524)
				)
			)
		)
		(duplicate_pad_numbers_are_jumpers no)
		(fp_line
			(start 0.508 -0.9398)
			(end -0.508 -0.9398)
			(stroke
				(width 0.1524)
				(type default)
			)
			(layer "F.SilkS")
		)
		(fp_line
			(start -0.508 -0.9398)
			(end -0.508 0.9398)
			(stroke
				(width 0.1524)
				(type default)
			)
			(layer "F.SilkS")
		)
		(fp_rect
			(start -0.508 0.9398)
			(end 0.508 -0.9398)
			(stroke
				(width 0)
				(type default)
			)
			(fill no)
			(layer "F.CrtYd")
		)
		(fp_rect
			(start -0.508 0.9398)
			(end 0.508 -0.9398)
			(stroke
				(width 0)
				(type default)
			)
			(fill no)
			(layer "F.Fab")
		)
		(pad "1" smd custom
			(at 0 -0.4445 180)
			(size 0.1397 0.1397)
			(layers "F.Cu" "F.Mask" "F.Paste")
			(net "VREF3")
			(options
				(clearance outline)
				(anchor circle)
			)
			(primitives
				(gr_poly
					(pts
						(arc
							(start -0.1778 -0.2794)
							(mid -0.249642 -0.249642)
							(end -0.2794 -0.1778)
						)
						(arc
							(start -0.2794 0.1778)
							(mid -0.249642 0.249642)
							(end -0.1778 0.2794)
						)
						(arc
							(start 0.1778 0.2794)
							(mid 0.249642 0.249642)
							(end 0.2794 0.1778)
						)
						(arc
							(start 0.2794 -0.1778)
							(mid 0.249642 -0.249642)
							(end 0.1778 -0.2794)
						)
					)
					(width 0)
					(fill yes)
				)
			)
		)
		(pad "2" smd custom
			(at 0 0.4445 180)
			(size 0.1397 0.1397)
			(layers "F.Cu" "F.Mask" "F.Paste")
			(net "P3V3")
			(options
				(clearance outline)
				(anchor circle)
			)
			(primitives
				(gr_poly
					(pts
						(arc
							(start -0.1778 -0.2794)
							(mid -0.249642 -0.249642)
							(end -0.2794 -0.1778)
						)
						(arc
							(start -0.2794 0.1778)
							(mid -0.249642 0.249642)
							(end -0.1778 0.2794)
						)
						(arc
							(start 0.1778 0.2794)
							(mid 0.249642 0.249642)
							(end 0.2794 0.1778)
						)
						(arc
							(start 0.2794 -0.1778)
							(mid 0.249642 -0.249642)
							(end 0.1778 -0.2794)
						)
					)
					(width 0)
					(fill yes)
				)
			)
		)
	)
	(footprint ""
		(layer "F.Cu")
		(at 185.600848 -58.472578)
		(property "Reference" "R395"
			(at 0 0 0)
			(layer "F.SilkS")
			(hide yes)
			(effects
				(font
					(size 1.27 1.27)
				)
			)
		)
		(property "Value" "10KR2F-2-GP"
			(at 0.064008 -3.993896 0)
			(unlocked yes)
			(layer "F.Fab")
			(hide yes)
			(effects
				(font
					(size 1.016 1.016)
					(thickness 0.1524)
				)
			)
		)
		(property "Device Type" "R402H16"
			(at 0.064008 -5.517896 0)
			(unlocked yes)
			(layer "F.Fab")
			(hide yes)
			(effects
				(font
					(size 1.016 1.016)
					(thickness 0.1524)
				)
			)
		)
		(duplicate_pad_numbers_are_jumpers no)
		(fp_line
			(start -0.508 -0.9398)
			(end -0.508 0.9398)
			(stroke
				(width 0.1524)
				(type default)
			)
			(layer "F.SilkS")
		)
		(fp_line
			(start 0.508 -0.9398)
			(end -0.508 -0.9398)
			(stroke
				(width 0.1524)
				(type default)
			)
			(layer "F.SilkS")
		)
		(fp_rect
			(start -0.508 0.9398)
			(end 0.508 -0.9398)
			(stroke
				(width 0)
				(type default)
			)
			(fill no)
			(layer "F.CrtYd")
		)
		(fp_rect
			(start -0.508 0.9398)
			(end 0.508 -0.9398)
			(stroke
				(width 0)
				(type default)
			)
			(fill no)
			(layer "F.Fab")
		)
		(pad "1" smd custom
			(at 0 -0.4445)
			(size 0.1397 0.1397)
			(layers "F.Cu" "F.Mask" "F.Paste")
			(net "P1V8_C")
			(options
				(clearance outline)
				(anchor circle)
			)
			(primitives
				(gr_poly
					(pts
						(arc
							(start -0.1778 -0.2794)
							(mid -0.249642 -0.249642)
							(end -0.2794 -0.1778)
						)
						(arc
							(start -0.2794 0.1778)
							(mid -0.249642 0.249642)
							(end -0.1778 0.2794)
						)
						(arc
							(start 0.1778 0.2794)
							(mid 0.249642 0.249642)
							(end 0.2794 0.1778)
						)
						(arc
							(start 0.2794 -0.1778)
							(mid 0.249642 -0.249642)
							(end 0.1778 -0.2794)
						)
					)
					(width 0)
					(fill yes)
				)
			)
		)
		(pad "2" smd custom
			(at 0 0.4445)
			(size 0.1397 0.1397)
			(layers "F.Cu" "F.Mask" "F.Paste")
			(net "XM_ADDR_1")
			(options
				(clearance outline)
				(anchor circle)
			)
			(primitives
				(gr_poly
					(pts
						(arc
							(start -0.1778 -0.2794)
							(mid -0.249642 -0.249642)
							(end -0.2794 -0.1778)
						)
						(arc
							(start -0.2794 0.1778)
							(mid -0.249642 0.249642)
							(end -0.1778 0.2794)
						)
						(arc
							(start 0.1778 0.2794)
							(mid 0.249642 0.249642)
							(end 0.2794 0.1778)
						)
						(arc
							(start 0.2794 -0.1778)
							(mid 0.249642 -0.249642)
							(end 0.1778 -0.2794)
						)
					)
					(width 0)
					(fill yes)
				)
			)
		)
	)
	(footprint ""
		(layer "F.Cu")
		(at 107.02925 -88.024208)
		(property "Reference" "TP40"
			(at 0 0 0)
			(layer "F.SilkS")
			(hide yes)
			(effects
				(font
					(size 1.27 1.27)
				)
			)
		)
		(property "Value" "TPAD28-2-GP"
			(at -0.0127 -1.6637 0)
			(unlocked yes)
			(layer "F.Fab")
			(hide yes)
			(effects
				(font
					(size 1.016 1.016)
					(thickness 0.1524)
				)
			)
		)
		(property "Device Type" "TPAD28"
			(at -0.0127 -3.1877 0)
			(unlocked yes)
			(layer "F.Fab")
			(hide yes)
			(effects
				(font
					(size 1.016 1.016)
					(thickness 0.1524)
				)
			)
		)
		(duplicate_pad_numbers_are_jumpers no)
		(fp_poly
			(pts
				(arc
					(start 0.3556 0)
					(mid -0.3556 0)
					(end 0.3556 0)
				)
			)
			(stroke
				(width 0)
				(type default)
			)
			(fill no)
			(layer "F.CrtYd")
		)
		(fp_poly
			(pts
				(arc
					(start 0.6096 0)
					(mid -0.6096 0)
					(end 0.6096 0)
				)
			)
			(stroke
				(width 0)
				(type default)
			)
			(fill no)
			(layer "F.Fab")
		)
		(pad "1" smd circle
			(at 0 0)
			(size 0.7112 0.7112)
			(layers "F.Cu" "F.Mask" "F.Paste")
			(net "JTAG_EXP_TMS")
		)
	)
	(footprint ""
		(layer "F.Cu")
		(at 68.453 -106.299 180)
		(property "Reference" "R88"
			(at 0 0 180)
			(layer "F.SilkS")
			(hide yes)
			(effects
				(font
					(size 1.27 1.27)
				)
			)
		)
		(property "Value" "0R2J-2-GP"
			(at 0.064008 -3.993896 180)
			(unlocked yes)
			(layer "F.Fab")
			(hide yes)
			(effects
				(font
					(size 1.016 1.016)
					(thickness 0.1524)
				)
			)
		)
		(property "Device Type" "R402H16"
			(at 0.064008 -5.517896 180)
			(unlocked yes)
			(layer "F.Fab")
			(hide yes)
			(effects
				(font
					(size 1.016 1.016)
					(thickness 0.1524)
				)
			)
		)
		(duplicate_pad_numbers_are_jumpers no)
		(fp_line
			(start 0.508 -0.9398)
			(end -0.508 -0.9398)
			(stroke
				(width 0.1524)
				(type default)
			)
			(layer "F.SilkS")
		)
		(fp_line
			(start -0.508 -0.9398)
			(end -0.508 0.9398)
			(stroke
				(width 0.1524)
				(type default)
			)
			(layer "F.SilkS")
		)
		(fp_rect
			(start -0.508 0.9398)
			(end 0.508 -0.9398)
			(stroke
				(width 0)
				(type default)
			)
			(fill no)
			(layer "F.CrtYd")
		)
		(fp_rect
			(start -0.508 0.9398)
			(end 0.508 -0.9398)
			(stroke
				(width 0)
				(type default)
			)
			(fill no)
			(layer "F.Fab")
		)
		(pad "1" smd custom
			(at 0 -0.4445 180)
			(size 0.1397 0.1397)
			(layers "F.Cu" "F.Mask" "F.Paste")
			(net "P3V3_EN")
			(options
				(clearance outline)
				(anchor circle)
			)
			(primitives
				(gr_poly
					(pts
						(arc
							(start -0.1778 -0.2794)
							(mid -0.249642 -0.249642)
							(end -0.2794 -0.1778)
						)
						(arc
							(start -0.2794 0.1778)
							(mid -0.249642 0.249642)
							(end -0.1778 0.2794)
						)
						(arc
							(start 0.1778 0.2794)
							(mid 0.249642 0.249642)
							(end 0.2794 0.1778)
						)
						(arc
							(start 0.2794 -0.1778)
							(mid 0.249642 -0.249642)
							(end 0.1778 -0.2794)
						)
					)
					(width 0)
					(fill yes)
				)
			)
		)
		(pad "2" smd custom
			(at 0 0.4445 180)
			(size 0.1397 0.1397)
			(layers "F.Cu" "F.Mask" "F.Paste")
			(net "P12V_SCC_PGOOD")
			(options
				(clearance outline)
				(anchor circle)
			)
			(primitives
				(gr_poly
					(pts
						(arc
							(start -0.1778 -0.2794)
							(mid -0.249642 -0.249642)
							(end -0.2794 -0.1778)
						)
						(arc
							(start -0.2794 0.1778)
							(mid -0.249642 0.249642)
							(end -0.1778 0.2794)
						)
						(arc
							(start 0.1778 0.2794)
							(mid 0.249642 0.249642)
							(end 0.2794 0.1778)
						)
						(arc
							(start 0.2794 -0.1778)
							(mid 0.249642 -0.249642)
							(end 0.1778 -0.2794)
						)
					)
					(width 0)
					(fill yes)
				)
			)
		)
	)
)
